(kicad_pcb
	(version 20260206)
	(generator "pcbnew")
	(generator_version "10.0")
	(general
		(thickness 1.6)
		(legacy_teardrops no)
	)
	(paper "A4")
	(title_block
		(title "03242023_DA0F0TMBIJ0_F0T_Motherboard_J_brd_V01_OCP.brd")
		(comment 1 "Grand Teton / footprint 1682 of 6105 (U1), pads 1275-1381 of 4677")
	)
	(layers
		(0 "F.Cu" signal "TOP")
		(4 "In1.Cu" signal "GND")
		(6 "In2.Cu" signal "IN1")
		(8 "In3.Cu" signal "GND1")
		(10 "In4.Cu" signal "IN2")
		(12 "In5.Cu" signal "GND2")
		(14 "In6.Cu" signal "IN3")
		(16 "In7.Cu" signal "GND3")
		(18 "In8.Cu" signal "VCC")
		(20 "In9.Cu" signal "VCC1")
		(22 "In10.Cu" signal "GND4")
		(24 "In11.Cu" signal "IN4")
		(26 "In12.Cu" signal "GND5")
		(28 "In13.Cu" signal "IN5")
		(30 "In14.Cu" signal "GND6")
		(32 "In15.Cu" signal "IN6")
		(34 "In16.Cu" signal "GND7")
		(2 "B.Cu" signal "BOTTOM")
		(9 "F.Adhes" user "F.Adhesive")
		(11 "B.Adhes" user "B.Adhesive")
		(13 "F.Paste" user "Package Geometry/Pastemask Top")
		(15 "B.Paste" user "Package Geometry/Pastemask Bottom")
		(5 "F.SilkS" user "Ref Des/Silkscreen Top")
		(7 "B.SilkS" user "Ref Des/Silkscreen Bottom")
		(1 "F.Mask" user "Board Geometry/Soldermask Top")
		(3 "B.Mask" user "Board Geometry/Soldermask Bottom")
		(17 "Dwgs.User" user "User.Drawings")
		(19 "Cmts.User" user "User.Comments")
		(21 "Eco1.User" user "User.Eco1")
		(23 "Eco2.User" user "User.Eco2")
		(25 "Edge.Cuts" user "Board Geometry/Outline")
		(27 "Margin" user)
		(31 "F.CrtYd" user "Package Geometry/Place Bound Top")
		(29 "B.CrtYd" user "Package Geometry/Place Bound Bottom")
		(35 "F.Fab" user "Ref Des/Assembly Top")
		(33 "B.Fab" user "Ref Des/Assembly Bottom")
	)
	(footprint ""
		(layer "F.Cu")
		(at 111.93018 -251.76988 90)
		(property "Reference" "U1"
			(at -74.913236 41.548812 0)
			(unlocked yes)
			(layer "F.SilkS")
			(effects
				(font
					(size 1.6002 1.1938)
					(thickness 0.1524)
				)
				(justify left)
			)
		)
		(property "Value" ""
			(at 0 0 90)
			(layer "F.Fab")
			(effects
				(font
					(size 1.27 1.27)
				)
			)
		)
		(duplicate_pad_numbers_are_jumpers no)
		(pad "BM77" smd circle
			(at 26.030682 -2.999486 270)
			(size 0.4318 0.4318)
			(layers "F.Cu" "F.Mask" "F.Paste")
			(net "GND")
		)
		(pad "BM79" smd circle
			(at 27.658314 -2.999486 270)
			(size 0.4318 0.4318)
			(layers "F.Cu" "F.Mask" "F.Paste")
			(net "PVCCIN_CPU1")
		)
		(pad "BM81" smd circle
			(at 29.2862 -2.999486 270)
			(size 0.4318 0.4318)
			(layers "F.Cu" "F.Mask" "F.Paste")
			(net "PVCCIN_CPU1")
		)
		(pad "BM83" smd circle
			(at 30.914086 -2.999486 270)
			(size 0.4318 0.4318)
			(layers "F.Cu" "F.Mask" "F.Paste")
			(net "PVCCIN_CPU1")
		)
		(pad "BM85" smd circle
			(at 32.541718 -2.999486 270)
			(size 0.4318 0.4318)
			(layers "F.Cu" "F.Mask" "F.Paste")
			(net "PVCCIN_CPU1")
		)
		(pad "BM87" smd circle
			(at 34.169604 -2.999486 270)
			(size 0.4318 0.4318)
			(layers "F.Cu" "F.Mask" "F.Paste")
			(net "PVCCIN_CPU1")
		)
		(pad "BM89" smd circle
			(at 35.797236 -2.999486 270)
			(size 0.4318 0.4318)
			(layers "F.Cu" "F.Mask" "F.Paste")
			(net "PVCCIN_CPU1")
		)
		(pad "BM91" smd oval
			(at 37.425122 -2.999486)
			(size 0.381 0.4826)
			(drill
				(offset 0 -0.0508)
			)
			(layers "F.Cu" "F.Mask" "F.Paste")
			(net "PVCCIN_CPU1")
		)
		(pad "BN3" smd circle
			(at -35.797236 -2.639314 270)
			(size 0.4318 0.4318)
			(layers "F.Cu" "F.Mask" "F.Paste")
			(net "UPI_CPU1_CPU0_P0P1_DP<22>")
		)
		(pad "BN5" smd circle
			(at -34.169604 -2.639314 270)
			(size 0.4318 0.4318)
			(layers "F.Cu" "F.Mask" "F.Paste")
			(net "UPI_CPU0_CPU1_P1P0_DN<21>")
		)
		(pad "BN7" smd circle
			(at -32.541718 -2.639314 270)
			(size 0.4318 0.4318)
			(layers "F.Cu" "F.Mask" "F.Paste")
			(net "PVCCD_HV_CPU1")
		)
		(pad "BN9" smd circle
			(at -30.914086 -2.639314 270)
			(size 0.4318 0.4318)
			(layers "F.Cu" "F.Mask" "F.Paste")
			(net "P5E_CPU1_PE1_RX_DP<10>")
		)
		(pad "BN11" smd circle
			(at -29.2862 -2.639314 270)
			(size 0.4318 0.4318)
			(layers "F.Cu" "F.Mask" "F.Paste")
			(net "VSENSE_PVCCD_HV_CPU1_DN")
		)
		(pad "BN13" smd circle
			(at -27.658314 -2.639314 270)
			(size 0.4318 0.4318)
			(layers "F.Cu" "F.Mask" "F.Paste")
			(net "P5E_CPU1_PE1_TX_DN<11>")
		)
		(pad "BN15" smd circle
			(at -26.030682 -2.639314 270)
			(size 0.4318 0.4318)
			(layers "F.Cu" "F.Mask" "F.Paste")
			(net "PVCCINFAON_CPU1")
		)
		(pad "BN17" smd circle
			(at -24.402796 -2.639314 270)
			(size 0.4318 0.4318)
			(layers "F.Cu" "F.Mask" "F.Paste")
			(net "TP_DMI_CPU1_PCH_RX_C_DN<5>")
		)
		(pad "BN19" smd circle
			(at -22.77491 -2.639314 270)
			(size 0.4318 0.4318)
			(layers "F.Cu" "F.Mask" "F.Paste")
			(net "PVNN_MAIN_CPU1")
		)
		(pad "BN21" smd circle
			(at -21.147278 -2.639314 270)
			(size 0.4318 0.4318)
			(layers "F.Cu" "F.Mask" "F.Paste")
			(net "NC_CPU1_PE0_APROBE<0>")
		)
		(pad "BN23" smd circle
			(at -19.519392 -2.639314 270)
			(size 0.4318 0.4318)
			(layers "F.Cu" "F.Mask" "F.Paste")
			(net "H_CPU1_BMCINIT_LVC1")
		)
		(pad "BN25" smd circle
			(at -17.89176 -2.639314 270)
			(size 0.4318 0.4318)
			(layers "F.Cu" "F.Mask" "F.Paste")
			(net "DBP_CPU1_MBP1_GTL_R_N")
		)
		(pad "BN27" smd circle
			(at -16.263874 -2.639314 270)
			(size 0.4318 0.4318)
			(layers "F.Cu" "F.Mask" "F.Paste")
			(net "TP_TRC_CPU1_PTI<12>")
		)
		(pad "BN29" smd circle
			(at -14.635988 -2.639314 270)
			(size 0.4318 0.4318)
			(layers "F.Cu" "F.Mask" "F.Paste")
			(net "TP_TRC_CPU1_PTI<14>")
		)
		(pad "BN31" smd circle
			(at -13.008356 -2.639314 270)
			(size 0.4318 0.4318)
			(layers "F.Cu" "F.Mask" "F.Paste")
			(net "GND")
		)
		(pad "BN33" smd circle
			(at -11.380724 -2.639314 270)
			(size 0.4318 0.4318)
			(layers "F.Cu" "F.Mask" "F.Paste")
			(net "PVCCIN_CPU1")
		)
		(pad "BN35" smd circle
			(at -9.752838 -2.639314 270)
			(size 0.4318 0.4318)
			(layers "F.Cu" "F.Mask" "F.Paste")
			(net "PVCCIN_CPU1")
		)
		(pad "BN37" smd circle
			(at -8.124952 -2.639314 270)
			(size 0.4318 0.4318)
			(layers "F.Cu" "F.Mask" "F.Paste")
			(net "PVCCIN_CPU1")
		)
		(pad "BN39" smd circle
			(at -6.49732 -2.639314 270)
			(size 0.4318 0.4318)
			(layers "F.Cu" "F.Mask" "F.Paste")
			(net "PVCCIN_CPU1")
		)
		(pad "BN41" smd circle
			(at -4.869434 -2.639314 270)
			(size 0.4318 0.4318)
			(layers "F.Cu" "F.Mask" "F.Paste")
			(net "PVCCIN_CPU1")
		)
		(pad "BN43" smd circle
			(at -3.241802 -2.639314 270)
			(size 0.4318 0.4318)
			(layers "F.Cu" "F.Mask" "F.Paste")
			(net "PVCCIN_CPU1")
		)
		(pad "BN45" smd circle
			(at -1.613916 -2.639314 270)
			(size 0.4318 0.4318)
			(layers "F.Cu" "F.Mask" "F.Paste")
			(net "PVCCIN_CPU1")
		)
		(pad "BN48" smd circle
			(at 2.427732 -2.529586 270)
			(size 0.4318 0.4318)
			(layers "F.Cu" "F.Mask" "F.Paste")
			(net "PVCCIN_CPU1")
		)
		(pad "BN50" smd circle
			(at 4.055618 -2.529586 270)
			(size 0.4318 0.4318)
			(layers "F.Cu" "F.Mask" "F.Paste")
			(net "PVCCIN_CPU1")
		)
		(pad "BN52" smd circle
			(at 5.68325 -2.529586 270)
			(size 0.4318 0.4318)
			(layers "F.Cu" "F.Mask" "F.Paste")
			(net "PVCCIN_CPU1")
		)
		(pad "BN54" smd circle
			(at 7.311136 -2.529586 270)
			(size 0.4318 0.4318)
			(layers "F.Cu" "F.Mask" "F.Paste")
			(net "PVCCIN_CPU1")
		)
		(pad "BN56" smd circle
			(at 8.939022 -2.529586 270)
			(size 0.4318 0.4318)
			(layers "F.Cu" "F.Mask" "F.Paste")
			(net "PVCCIN_CPU1")
		)
		(pad "BN58" smd circle
			(at 10.566654 -2.529586 270)
			(size 0.4318 0.4318)
			(layers "F.Cu" "F.Mask" "F.Paste")
			(net "PVCCIN_CPU1")
		)
		(pad "BN60" smd circle
			(at 12.19454 -2.529586 270)
			(size 0.4318 0.4318)
			(layers "F.Cu" "F.Mask" "F.Paste")
			(net "PVCCIN_CPU1")
		)
		(pad "BN62" smd circle
			(at 13.822426 -2.529586 270)
			(size 0.4318 0.4318)
			(layers "F.Cu" "F.Mask" "F.Paste")
			(net "GND")
		)
		(pad "BN64" smd circle
			(at 15.450058 -2.529586 270)
			(size 0.4318 0.4318)
			(layers "F.Cu" "F.Mask" "F.Paste")
			(net "FM_CPU1_PKGID2")
		)
		(pad "BN66" smd circle
			(at 17.07769 -2.529586 270)
			(size 0.4318 0.4318)
			(layers "F.Cu" "F.Mask" "F.Paste")
			(net "TP_TRC_CPU1_PTI<31>")
		)
		(pad "BN68" smd circle
			(at 18.705576 -2.529586 270)
			(size 0.4318 0.4318)
			(layers "F.Cu" "F.Mask" "F.Paste")
			(net "TP_TRC_CPU1_PTI<26>")
		)
		(pad "BN70" smd circle
			(at 20.333462 -2.529586 270)
			(size 0.4318 0.4318)
			(layers "F.Cu" "F.Mask" "F.Paste")
			(net "GND")
		)
		(pad "BN72" smd circle
			(at 21.961094 -2.529586 270)
			(size 0.4318 0.4318)
			(layers "F.Cu" "F.Mask" "F.Paste")
			(net "UPI_CPU1_CPU0_P2P2_DP<23>")
		)
		(pad "BN74" smd circle
			(at 23.58898 -2.529586 270)
			(size 0.4318 0.4318)
			(layers "F.Cu" "F.Mask" "F.Paste")
			(net "UPI_CPU0_CPU1_P2P2_DN<21>")
		)
		(pad "BN76" smd circle
			(at 25.216612 -2.529586 270)
			(size 0.4318 0.4318)
			(layers "F.Cu" "F.Mask" "F.Paste")
			(net "UPI_CPU0_CPU1_P2P2_DP<19>")
		)
		(pad "BN78" smd circle
			(at 26.844498 -2.529586 270)
			(size 0.4318 0.4318)
			(layers "F.Cu" "F.Mask" "F.Paste")
			(net "PVCCIN_CPU1")
		)
		(pad "BN80" smd circle
			(at 28.472384 -2.529586 270)
			(size 0.4318 0.4318)
			(layers "F.Cu" "F.Mask" "F.Paste")
			(net "PVCCIN_CPU1")
		)
		(pad "BN82" smd circle
			(at 30.100016 -2.529586 270)
			(size 0.4318 0.4318)
			(layers "F.Cu" "F.Mask" "F.Paste")
			(net "PVCCIN_CPU1")
		)
		(pad "BN84" smd circle
			(at 31.727902 -2.529586 270)
			(size 0.4318 0.4318)
			(layers "F.Cu" "F.Mask" "F.Paste")
			(net "PVCCIN_CPU1")
		)
		(pad "BN86" smd circle
			(at 33.355534 -2.529586 270)
			(size 0.4318 0.4318)
			(layers "F.Cu" "F.Mask" "F.Paste")
			(net "PVCCIN_CPU1")
		)
		(pad "BN88" smd circle
			(at 34.98342 -2.529586 270)
			(size 0.4318 0.4318)
			(layers "F.Cu" "F.Mask" "F.Paste")
			(net "PVCCIN_CPU1")
		)
		(pad "BN90" smd oval
			(at 36.611306 -2.529586)
			(size 0.381 0.4826)
			(drill
				(offset 0 -0.0508)
			)
			(layers "F.Cu" "F.Mask" "F.Paste")
			(net "PVCCIN_CPU1")
		)
		(pad "BP2" smd oval
			(at -36.611306 -2.169668 180)
			(size 0.381 0.4826)
			(drill
				(offset 0 -0.0508)
			)
			(layers "F.Cu" "F.Mask" "F.Paste")
			(net "GND")
		)
		(pad "BP4" smd circle
			(at -34.98342 -2.169668 270)
			(size 0.4318 0.4318)
			(layers "F.Cu" "F.Mask" "F.Paste")
			(net "GND")
		)
		(pad "BP6" smd circle
			(at -33.355534 -2.169668 270)
			(size 0.4318 0.4318)
			(layers "F.Cu" "F.Mask" "F.Paste")
			(net "UPI_CPU0_CPU1_P1P0_DP<22>")
		)
		(pad "BP8" smd circle
			(at -31.727902 -2.169668 270)
			(size 0.4318 0.4318)
			(layers "F.Cu" "F.Mask" "F.Paste")
			(net "GND")
		)
		(pad "BP10" smd circle
			(at -30.100016 -2.169668 270)
			(size 0.4318 0.4318)
			(layers "F.Cu" "F.Mask" "F.Paste")
			(net "P5E_CPU1_PE1_RX_DN<10>")
		)
		(pad "BP12" smd circle
			(at -28.472384 -2.169668 270)
			(size 0.4318 0.4318)
			(layers "F.Cu" "F.Mask" "F.Paste")
			(net "GND")
		)
		(pad "BP14" smd circle
			(at -26.844498 -2.169668 270)
			(size 0.4318 0.4318)
			(layers "F.Cu" "F.Mask" "F.Paste")
			(net "P5E_CPU1_PE1_TX_DN<10>")
		)
		(pad "BP16" smd circle
			(at -25.216612 -2.169668 270)
			(size 0.4318 0.4318)
			(layers "F.Cu" "F.Mask" "F.Paste")
			(net "GND")
		)
		(pad "BP18" smd circle
			(at -23.58898 -2.169668 270)
			(size 0.4318 0.4318)
			(layers "F.Cu" "F.Mask" "F.Paste")
			(net "TP_DMI_CPU1_PCH_RX_C_DN<6>")
		)
		(pad "BP20" smd circle
			(at -21.961094 -2.169668 270)
			(size 0.4318 0.4318)
			(layers "F.Cu" "F.Mask" "F.Paste")
			(net "GND")
		)
		(pad "BP22" smd circle
			(at -20.333462 -2.169668 270)
			(size 0.4318 0.4318)
			(layers "F.Cu" "F.Mask" "F.Paste")
			(net "NC_CPU1_MDFI_DIE00_EW0")
		)
		(pad "BP24" smd circle
			(at -18.705576 -2.169668 270)
			(size 0.4318 0.4318)
			(layers "F.Cu" "F.Mask" "F.Paste")
			(net "H_CPU1_CATERR_LVC1_R_N")
		)
		(pad "BP26" smd circle
			(at -17.07769 -2.169668 270)
			(size 0.4318 0.4318)
			(layers "F.Cu" "F.Mask" "F.Paste")
			(net "H_CPU1_PRDY_QS_GTL_R_N")
		)
		(pad "BP28" smd circle
			(at -15.450058 -2.169668 270)
			(size 0.4318 0.4318)
			(layers "F.Cu" "F.Mask" "F.Paste")
			(net "TP_TRC_CPU1_PTI<13>")
		)
		(pad "BP30" smd circle
			(at -13.822426 -2.169668 270)
			(size 0.4318 0.4318)
			(layers "F.Cu" "F.Mask" "F.Paste")
			(net "TP_TRC_CPU1_PTI<15>")
		)
		(pad "BP32" smd circle
			(at -12.19454 -2.169668 270)
			(size 0.4318 0.4318)
			(layers "F.Cu" "F.Mask" "F.Paste")
			(net "PVCCIN_CPU1")
		)
		(pad "BP34" smd circle
			(at -10.566654 -2.169668 270)
			(size 0.4318 0.4318)
			(layers "F.Cu" "F.Mask" "F.Paste")
			(net "PVCCIN_CPU1")
		)
		(pad "BP36" smd circle
			(at -8.939022 -2.169668 270)
			(size 0.4318 0.4318)
			(layers "F.Cu" "F.Mask" "F.Paste")
			(net "PVCCIN_CPU1")
		)
		(pad "BP38" smd circle
			(at -7.311136 -2.169668 270)
			(size 0.4318 0.4318)
			(layers "F.Cu" "F.Mask" "F.Paste")
			(net "PVCCIN_CPU1")
		)
		(pad "BP40" smd circle
			(at -5.68325 -2.169668 270)
			(size 0.4318 0.4318)
			(layers "F.Cu" "F.Mask" "F.Paste")
			(net "PVCCIN_CPU1")
		)
		(pad "BP42" smd circle
			(at -4.055618 -2.169668 270)
			(size 0.4318 0.4318)
			(layers "F.Cu" "F.Mask" "F.Paste")
			(net "PVCCIN_CPU1")
		)
		(pad "BP44" smd circle
			(at -2.427732 -2.169668 270)
			(size 0.4318 0.4318)
			(layers "F.Cu" "F.Mask" "F.Paste")
			(net "PVCCIN_CPU1")
		)
		(pad "BP47" smd circle
			(at 1.613916 -2.059686 270)
			(size 0.4318 0.4318)
			(layers "F.Cu" "F.Mask" "F.Paste")
			(net "PVCCIN_CPU1")
		)
		(pad "BP49" smd circle
			(at 3.241802 -2.059686 270)
			(size 0.4318 0.4318)
			(layers "F.Cu" "F.Mask" "F.Paste")
			(net "PVCCIN_CPU1")
		)
		(pad "BP51" smd circle
			(at 4.869434 -2.059686 270)
			(size 0.4318 0.4318)
			(layers "F.Cu" "F.Mask" "F.Paste")
			(net "PVCCIN_CPU1")
		)
		(pad "BP53" smd circle
			(at 6.49732 -2.059686 270)
			(size 0.4318 0.4318)
			(layers "F.Cu" "F.Mask" "F.Paste")
			(net "PVCCIN_CPU1")
		)
		(pad "BP55" smd circle
			(at 8.124952 -2.059686 270)
			(size 0.4318 0.4318)
			(layers "F.Cu" "F.Mask" "F.Paste")
			(net "PVCCIN_CPU1")
		)
		(pad "BP57" smd circle
			(at 9.752838 -2.059686 270)
			(size 0.4318 0.4318)
			(layers "F.Cu" "F.Mask" "F.Paste")
			(net "PVCCIN_CPU1")
		)
		(pad "BP59" smd circle
			(at 11.380724 -2.059686 270)
			(size 0.4318 0.4318)
			(layers "F.Cu" "F.Mask" "F.Paste")
			(net "PVCCIN_CPU1")
		)
		(pad "BP61" smd circle
			(at 13.008356 -2.059686 270)
			(size 0.4318 0.4318)
			(layers "F.Cu" "F.Mask" "F.Paste")
			(net "PVCCIN_CPU1")
		)
		(pad "BP63" smd circle
			(at 14.635988 -2.059686 270)
			(size 0.4318 0.4318)
			(layers "F.Cu" "F.Mask" "F.Paste")
			(net "GND")
		)
		(pad "BP65" smd circle
			(at 16.263874 -2.059686 270)
			(size 0.4318 0.4318)
			(layers "F.Cu" "F.Mask" "F.Paste")
			(net "NC_CPU1_SOC_SPARE5")
		)
		(pad "BP67" smd circle
			(at 17.89176 -2.059686 270)
			(size 0.4318 0.4318)
			(layers "F.Cu" "F.Mask" "F.Paste")
			(net "CPU1_RSVD<64>")
		)
		(pad "BP69" smd circle
			(at 19.519392 -2.059686 270)
			(size 0.4318 0.4318)
			(layers "F.Cu" "F.Mask" "F.Paste")
			(net "CPU1_RSVD<65>")
		)
		(pad "BP71" smd circle
			(at 21.147278 -2.059686 270)
			(size 0.4318 0.4318)
			(layers "F.Cu" "F.Mask" "F.Paste")
			(net "GND")
		)
		(pad "BP73" smd circle
			(at 22.77491 -2.059686 270)
			(size 0.4318 0.4318)
			(layers "F.Cu" "F.Mask" "F.Paste")
			(net "GND")
		)
		(pad "BP75" smd circle
			(at 24.402796 -2.059686 270)
			(size 0.4318 0.4318)
			(layers "F.Cu" "F.Mask" "F.Paste")
			(net "GND")
		)
		(pad "BP77" smd circle
			(at 26.030682 -2.059686 270)
			(size 0.4318 0.4318)
			(layers "F.Cu" "F.Mask" "F.Paste")
			(net "GND")
		)
		(pad "BP79" smd circle
			(at 27.658314 -2.059686 270)
			(size 0.4318 0.4318)
			(layers "F.Cu" "F.Mask" "F.Paste")
			(net "PVCCIN_CPU1")
		)
		(pad "BP81" smd circle
			(at 29.2862 -2.059686 270)
			(size 0.4318 0.4318)
			(layers "F.Cu" "F.Mask" "F.Paste")
			(net "PVCCIN_CPU1")
		)
		(pad "BP83" smd circle
			(at 30.914086 -2.059686 270)
			(size 0.4318 0.4318)
			(layers "F.Cu" "F.Mask" "F.Paste")
			(net "PVCCIN_CPU1")
		)
		(pad "BP85" smd circle
			(at 32.541718 -2.059686 270)
			(size 0.4318 0.4318)
			(layers "F.Cu" "F.Mask" "F.Paste")
			(net "PVCCIN_CPU1")
		)
		(pad "BP87" smd circle
			(at 34.169604 -2.059686 270)
			(size 0.4318 0.4318)
			(layers "F.Cu" "F.Mask" "F.Paste")
			(net "PVCCIN_CPU1")
		)
		(pad "BP89" smd circle
			(at 35.797236 -2.059686 270)
			(size 0.4318 0.4318)
			(layers "F.Cu" "F.Mask" "F.Paste")
			(net "PVCCIN_CPU1")
		)
		(pad "BR3" smd circle
			(at -35.797236 -1.699514 270)
			(size 0.4318 0.4318)
			(layers "F.Cu" "F.Mask" "F.Paste")
			(net "UPI_CPU1_CPU0_P0P1_DN<22>")
		)
		(pad "BR5" smd circle
			(at -34.169604 -1.699514 270)
			(size 0.4318 0.4318)
			(layers "F.Cu" "F.Mask" "F.Paste")
			(net "GND")
		)
		(pad "BR7" smd circle
			(at -32.541718 -1.699514 270)
			(size 0.4318 0.4318)
			(layers "F.Cu" "F.Mask" "F.Paste")
			(net "UPI_CPU0_CPU1_P1P0_DN<22>")
		)
		(pad "BR9" smd circle
			(at -30.914086 -1.699514 270)
			(size 0.4318 0.4318)
			(layers "F.Cu" "F.Mask" "F.Paste")
			(net "GND")
		)
		(pad "BR11" smd circle
			(at -29.2862 -1.699514 270)
			(size 0.4318 0.4318)
			(layers "F.Cu" "F.Mask" "F.Paste")
			(net "P5E_CPU1_PE1_RX_DN<9>")
		)
		(pad "BR13" smd circle
			(at -27.658314 -1.699514 270)
			(size 0.4318 0.4318)
			(layers "F.Cu" "F.Mask" "F.Paste")
			(net "GND")
		)
		(pad "BR15" smd circle
			(at -26.030682 -1.699514 270)
			(size 0.4318 0.4318)
			(layers "F.Cu" "F.Mask" "F.Paste")
			(net "P5E_CPU1_PE1_TX_DP<10>")
		)
		(pad "BR17" smd circle
			(at -24.402796 -1.699514 270)
			(size 0.4318 0.4318)
			(layers "F.Cu" "F.Mask" "F.Paste")
			(net "GND")
		)
		(pad "BR19" smd circle
			(at -22.77491 -1.699514 270)
			(size 0.4318 0.4318)
			(layers "F.Cu" "F.Mask" "F.Paste")
			(net "TP_DMI_CPU1_PCH_RX_C_DP<6>")
		)
		(pad "BR21" smd circle
			(at -21.147278 -1.699514 270)
			(size 0.4318 0.4318)
			(layers "F.Cu" "F.Mask" "F.Paste")
			(net "NC_CPU1_MDFI_DIE00_EW1")
		)
		(pad "BR23" smd circle
			(at -19.519392 -1.699514 270)
			(size 0.4318 0.4318)
			(layers "F.Cu" "F.Mask" "F.Paste")
			(net "TP_CPU1_BR23")
		)
	)
)
